(kicad_pcb
	(version 20260206)
	(generator "pcbnew")
	(generator_version "10.0")
	(general
		(thickness 1.6)
		(legacy_teardrops no)
	)
	(paper "A4")
	(title_block
		(title "v1-chassis-manager — T6M_CM_d_v01_1031_1645.brd")
		(comment 1 "Open CloudServer (Microsoft) / footprint 838 of 2512 (J35), pads 120-164 of 164")
	)
	(layers
		(0 "F.Cu" signal "TOP")
		(4 "In1.Cu" signal "GND1")
		(6 "In2.Cu" signal "IN1")
		(8 "In3.Cu" signal "VCC1")
		(10 "In4.Cu" signal "VCC2")
		(12 "In5.Cu" signal "GND2")
		(14 "In6.Cu" signal "IN2")
		(16 "In7.Cu" signal "IN3")
		(18 "In8.Cu" signal "GND3")
		(2 "B.Cu" signal "BOTTOM")
		(9 "F.Adhes" user "F.Adhesive")
		(11 "B.Adhes" user "B.Adhesive")
		(13 "F.Paste" user "Package Geometry/Pastemask Top")
		(15 "B.Paste" user "Package Geometry/Pastemask Bottom")
		(5 "F.SilkS" user "Ref Des/Silkscreen Top")
		(7 "B.SilkS" user "Ref Des/Silkscreen Bottom")
		(1 "F.Mask" user "Board Geometry/Soldermask Top")
		(3 "B.Mask" user "Board Geometry/Soldermask Bottom")
		(17 "Dwgs.User" user "User.Drawings")
		(19 "Cmts.User" user "User.Comments")
		(21 "Eco1.User" user "User.Eco1")
		(23 "Eco2.User" user "User.Eco2")
		(25 "Edge.Cuts" user "Board Geometry/Outline")
		(27 "Margin" user)
		(31 "F.CrtYd" user "Package Geometry/Place Bound Top")
		(29 "B.CrtYd" user "Package Geometry/Place Bound Bottom")
		(35 "F.Fab" user "Ref Des/Assembly Top")
		(33 "B.Fab" user "Ref Des/Assembly Bottom")
	)
	(footprint ""
		(layer "F.Cu")
		(at 54.515004 -205.199488 180)
		(property "Reference" "J35"
			(at -39.89832 -7.345934 0)
			(unlocked yes)
			(layer "F.SilkS")
			(effects
				(font
					(size 0.7874 0.5842)
					(thickness 0.1524)
				)
				(justify left)
			)
		)
		(property "Value" ""
			(at 0 0 180)
			(layer "F.Fab")
			(effects
				(font
					(size 1.27 1.27)
				)
			)
		)
		(duplicate_pad_numbers_are_jumpers no)
		(pad "B38" smd rect
			(at -2.500122 0 180)
			(size 0.762 4.2164)
			(layers "F.Cu" "F.Mask" "F.Paste")
			(net "UART_T2_NODE3_TXD_R")
		)
		(pad "B39" smd rect
			(at -1.500124 0 180)
			(size 0.762 4.2164)
			(layers "F.Cu" "F.Mask" "F.Paste")
			(net "UART_T2_NODE4_RXD_R")
		)
		(pad "B40" smd rect
			(at -0.499872 0 180)
			(size 0.762 4.2164)
			(layers "F.Cu" "F.Mask" "F.Paste")
			(net "UART_T2_NODE4_TXD_R")
		)
		(pad "B41" smd rect
			(at 0.499872 0 180)
			(size 0.762 4.2164)
			(layers "F.Cu" "F.Mask" "F.Paste")
			(net "GND")
		)
		(pad "B42" smd rect
			(at 1.500124 0 180)
			(size 0.762 4.2164)
			(layers "F.Cu" "F.Mask" "F.Paste")
			(net "I2C_PSU1_R_SCL")
		)
		(pad "B43" smd rect
			(at 2.500122 0 180)
			(size 0.762 4.2164)
			(layers "F.Cu" "F.Mask" "F.Paste")
			(net "I2C_PSU1_R_SDA")
		)
		(pad "B44" smd rect
			(at 3.50012 0 180)
			(size 0.762 4.2164)
			(layers "F.Cu" "F.Mask" "F.Paste")
			(net "GND")
		)
		(pad "B45" smd rect
			(at 4.500118 0 180)
			(size 0.762 4.2164)
			(layers "F.Cu" "F.Mask" "F.Paste")
			(net "PSU1_AC_OK_R")
		)
		(pad "B46" smd rect
			(at 5.500116 0 180)
			(size 0.762 4.2164)
			(layers "F.Cu" "F.Mask" "F.Paste")
			(net "PSU2_AC_OK_R")
		)
		(pad "B47" smd rect
			(at 6.500114 0 180)
			(size 0.762 4.2164)
			(layers "F.Cu" "F.Mask" "F.Paste")
			(net "PSU3_AC_OK_R")
		)
		(pad "B48" smd rect
			(at 7.500112 -0.499872 180)
			(size 0.762 3.2004)
			(layers "F.Cu" "F.Mask" "F.Paste")
			(net "PSU4_AC_OK_R")
		)
		(pad "B49" smd rect
			(at 8.50011 0 180)
			(size 0.762 4.2164)
			(layers "F.Cu" "F.Mask" "F.Paste")
			(net "PSU5_AC_OK_R")
		)
		(pad "B50" smd rect
			(at 9.500108 0 180)
			(size 0.762 4.2164)
			(layers "F.Cu" "F.Mask" "F.Paste")
			(net "PSU6_AC_OK_R")
		)
		(pad "B51" smd rect
			(at 10.500106 0 180)
			(size 0.762 4.2164)
			(layers "F.Cu" "F.Mask" "F.Paste")
			(net "GND")
		)
		(pad "B52" smd rect
			(at 11.500104 0 180)
			(size 0.762 4.2164)
			(layers "F.Cu" "F.Mask" "F.Paste")
			(net "UART_RTS_P5_L_N")
		)
		(pad "B53" smd rect
			(at 12.500102 0 180)
			(size 0.762 4.2164)
			(layers "F.Cu" "F.Mask" "F.Paste")
			(net "UART_DSR_P5_L_N")
		)
		(pad "B54" smd rect
			(at 13.5001 0 180)
			(size 0.762 4.2164)
			(layers "F.Cu" "F.Mask" "F.Paste")
			(net "UART_RX_P5_L")
		)
		(pad "B55" smd rect
			(at 14.500098 0 180)
			(size 0.762 4.2164)
			(layers "F.Cu" "F.Mask" "F.Paste")
			(net "UART_TX_P5_L")
		)
		(pad "B56" smd rect
			(at 15.500096 0 180)
			(size 0.762 4.2164)
			(layers "F.Cu" "F.Mask" "F.Paste")
			(net "UART_DTR_P5_L_N")
		)
		(pad "B57" smd rect
			(at 16.500094 0 180)
			(size 0.762 4.2164)
			(layers "F.Cu" "F.Mask" "F.Paste")
			(net "UART_CTS_P5_L_N")
		)
		(pad "B58" smd rect
			(at 17.500092 0 180)
			(size 0.762 4.2164)
			(layers "F.Cu" "F.Mask" "F.Paste")
			(net "UART_RI_P5_L_N_R")
		)
		(pad "B59" smd rect
			(at 18.50009 0 180)
			(size 0.762 4.2164)
			(layers "F.Cu" "F.Mask" "F.Paste")
			(net "GND")
		)
		(pad "B60" smd rect
			(at 19.500088 0 180)
			(size 0.762 4.2164)
			(layers "F.Cu" "F.Mask" "F.Paste")
			(net "UART_RTS_P1_L_N")
		)
		(pad "B61" smd rect
			(at 20.500086 0 180)
			(size 0.762 4.2164)
			(layers "F.Cu" "F.Mask" "F.Paste")
			(net "UART_DSR_P1_L_N")
		)
		(pad "B62" smd rect
			(at 21.500084 0 180)
			(size 0.762 4.2164)
			(layers "F.Cu" "F.Mask" "F.Paste")
			(net "UART_RX_P1_L")
		)
		(pad "B63" smd rect
			(at 22.500082 0 180)
			(size 0.762 4.2164)
			(layers "F.Cu" "F.Mask" "F.Paste")
			(net "UART_TX_P1_L")
		)
		(pad "B64" smd rect
			(at 23.50008 0 180)
			(size 0.762 4.2164)
			(layers "F.Cu" "F.Mask" "F.Paste")
			(net "UART_DTR_P1_L_N")
		)
		(pad "B65" smd rect
			(at 24.500078 0 180)
			(size 0.762 4.2164)
			(layers "F.Cu" "F.Mask" "F.Paste")
			(net "UART_CTS_P1_L_N")
		)
		(pad "B66" smd rect
			(at 25.500076 0 180)
			(size 0.762 4.2164)
			(layers "F.Cu" "F.Mask" "F.Paste")
			(net "GND")
		)
		(pad "B67" smd rect
			(at 26.500074 0 180)
			(size 0.762 4.2164)
			(layers "F.Cu" "F.Mask" "F.Paste")
			(net "Net_2332")
		)
		(pad "B68" smd rect
			(at 27.500072 0 180)
			(size 0.762 4.2164)
			(layers "F.Cu" "F.Mask" "F.Paste")
			(net "GND61")
		)
		(pad "B69" smd rect
			(at 28.50007 0 180)
			(size 0.762 4.2164)
			(layers "F.Cu" "F.Mask" "F.Paste")
			(net "GND62")
		)
		(pad "B70" smd rect
			(at 29.500068 0 180)
			(size 0.762 4.2164)
			(layers "F.Cu" "F.Mask" "F.Paste")
			(net "Net_2331")
		)
		(pad "B71" smd rect
			(at 30.500066 0 180)
			(size 0.762 4.2164)
			(layers "F.Cu" "F.Mask" "F.Paste")
			(net "GND")
		)
		(pad "B72" smd rect
			(at 31.500064 0 180)
			(size 0.762 4.2164)
			(layers "F.Cu" "F.Mask" "F.Paste")
			(net "LAN1_P3_P")
		)
		(pad "B73" smd rect
			(at 32.500062 0 180)
			(size 0.762 4.2164)
			(layers "F.Cu" "F.Mask" "F.Paste")
			(net "LAN1_P3_N")
		)
		(pad "B74" smd rect
			(at 33.50006 0 180)
			(size 0.762 4.2164)
			(layers "F.Cu" "F.Mask" "F.Paste")
			(net "GND")
		)
		(pad "B75" smd rect
			(at 34.500058 0 180)
			(size 0.762 4.2164)
			(layers "F.Cu" "F.Mask" "F.Paste")
			(net "LAN1_P4_P")
		)
		(pad "B76" smd rect
			(at 35.500056 0 180)
			(size 0.762 4.2164)
			(layers "F.Cu" "F.Mask" "F.Paste")
			(net "LAN1_P4_N")
		)
		(pad "B77" smd rect
			(at 36.500054 0 180)
			(size 0.762 4.2164)
			(layers "F.Cu" "F.Mask" "F.Paste")
			(net "GND")
		)
		(pad "B78" smd rect
			(at 37.500052 0 180)
			(size 0.762 4.2164)
			(layers "F.Cu" "F.Mask" "F.Paste")
			(net "CM_PWR_CTL_IN")
		)
		(pad "B79" smd rect
			(at 38.50005 0 180)
			(size 0.762 4.2164)
			(layers "F.Cu" "F.Mask" "F.Paste")
			(net "P12V_PDB")
		)
		(pad "B80" smd rect
			(at 39.500048 0 180)
			(size 0.762 4.2164)
			(layers "F.Cu" "F.Mask" "F.Paste")
			(net "P12V_PDB")
		)
		(pad "B81" smd rect
			(at 40.500046 -0.499872 180)
			(size 0.762 3.2004)
			(layers "F.Cu" "F.Mask" "F.Paste")
			(net "MATE_R_N")
		)
		(pad "B82" smd rect
			(at 41.500044 0 180)
			(size 0.762 4.2164)
			(layers "F.Cu" "F.Mask" "F.Paste")
			(net "P12V_PDB")
		)
	)
)
